(kicad_pcb
	(version 20260206)
	(generator "pcbnew")
	(generator_version "10.0")
	(general
		(thickness 1.6)
		(legacy_teardrops no)
	)
	(paper "A4")
	(title_block
		(title "timecard-production-celestica-r4006 — R4006-B0001-02_R01.brd")
		(comment 1 "Time Appliance Project (Time Card) / footprints 1029-1033 of 1113")
	)
	(layers
		(0 "F.Cu" signal "TOP")
		(4 "In1.Cu" signal "L02_GND1")
		(6 "In2.Cu" signal "L03_SIG1")
		(8 "In3.Cu" signal "L04_GND2")
		(10 "In4.Cu" signal "L05_VCC1")
		(12 "In5.Cu" signal "L06_VCC2")
		(14 "In6.Cu" signal "L07_GND3")
		(16 "In7.Cu" signal "L08_SIG2")
		(18 "In8.Cu" signal "L09_GND4")
		(2 "B.Cu" signal "BOTTOM")
		(9 "F.Adhes" user "F.Adhesive")
		(11 "B.Adhes" user "B.Adhesive")
		(13 "F.Paste" user "Package Geometry/Pastemask Top")
		(15 "B.Paste" user "Package Geometry/Pastemask Bottom")
		(5 "F.SilkS" user "Ref Des/Silkscreen Top")
		(7 "B.SilkS" user "Ref Des/Silkscreen Bottom")
		(1 "F.Mask" user "Board Geometry/Soldermask Top")
		(3 "B.Mask" user "Board Geometry/Soldermask Bottom")
		(17 "Dwgs.User" user "User.Drawings")
		(19 "Cmts.User" user "User.Comments")
		(21 "Eco1.User" user "User.Eco1")
		(23 "Eco2.User" user "User.Eco2")
		(25 "Edge.Cuts" user "Board Geometry/Outline")
		(27 "Margin" user)
		(31 "F.CrtYd" user "Package Geometry/Place Bound Top")
		(29 "B.CrtYd" user "Package Geometry/Place Bound Bottom")
		(35 "F.Fab" user "Ref Des/Assembly Top")
		(33 "B.Fab" user "Ref Des/Assembly Bottom")
	)
	(footprint ""
		(layer "B.Cu")
		(at 41.783 -98.679 180)
		(property "Reference" "R31"
			(at 0.762 1.23063 0)
			(unlocked yes)
			(layer "B.SilkS")
			(effects
				(font
					(size 0.7874 0.5842)
					(thickness 0.1524)
				)
				(justify mirror)
			)
		)
		(property "Value" "VAL*"
			(at -0.02032 2.13233 180)
			(unlocked yes)
			(layer "B.Fab")
			(hide yes)
			(effects
				(font
					(size 0.7874 0.5842)
					(thickness 0.1524)
				)
				(justify mirror)
			)
		)
		(property "Tolerance" "TOL*"
			(at -0.044704 3.05435 180)
			(unlocked yes)
			(layer "Cmts.User")
			(hide yes)
			(effects
				(font
					(size 0.7874 0.5842)
					(thickness 0.1524)
				)
				(justify mirror)
			)
		)
		(property "User Part Number" "PARTNUM*"
			(at -0.02032 4.024884 180)
			(unlocked yes)
			(layer "Cmts.User")
			(hide yes)
			(effects
				(font
					(size 0.7874 0.5842)
					(thickness 0.1524)
				)
				(justify mirror)
			)
		)
		(property "Device Type" "RESISTOR-G155-100R0-J0,0OHM,-"
			(at -0.008382 1.210564 180)
			(unlocked yes)
			(layer "B.Fab")
			(hide yes)
			(effects
				(font
					(size 0.7874 0.5842)
					(thickness 0.1524)
				)
				(justify mirror)
			)
		)
		(duplicate_pad_numbers_are_jumpers no)
		(fp_line
			(start 1.143 0.5588)
			(end -1.143 0.5588)
			(stroke
				(width 0.1)
				(type default)
			)
			(layer "B.SilkS")
		)
		(fp_line
			(start 1.143 -0.5588)
			(end 1.143 0.5588)
			(stroke
				(width 0.1)
				(type default)
			)
			(layer "B.SilkS")
		)
		(fp_line
			(start -1.143 0.5588)
			(end -1.143 -0.5588)
			(stroke
				(width 0.1)
				(type default)
			)
			(layer "B.SilkS")
		)
		(fp_line
			(start -1.143 -0.5588)
			(end 1.143 -0.5588)
			(stroke
				(width 0.1)
				(type default)
			)
			(layer "B.SilkS")
		)
		(fp_poly
			(pts
				(xy 1.143 0.5588) (xy -1.143 0.5588) (xy -1.143 -0.5588) (xy 1.143 -0.5588)
			)
			(stroke
				(width 0)
				(type default)
			)
			(fill no)
			(layer "B.CrtYd")
		)
		(fp_line
			(start 0.508 0.3048)
			(end -0.508 0.3048)
			(stroke
				(width 0.1)
				(type default)
			)
			(layer "B.Fab")
		)
		(fp_line
			(start 0.508 -0.3048)
			(end 0.508 0.3048)
			(stroke
				(width 0.1)
				(type default)
			)
			(layer "B.Fab")
		)
		(fp_line
			(start -0.508 0.3048)
			(end -0.508 -0.3048)
			(stroke
				(width 0.1)
				(type default)
			)
			(layer "B.Fab")
		)
		(fp_line
			(start -0.508 -0.3048)
			(end 0.508 -0.3048)
			(stroke
				(width 0.1)
				(type default)
			)
			(layer "B.Fab")
		)
		(pad "1" smd rect
			(at 0.5334 0)
			(size 0.7112 0.6096)
			(layers "B.Cu" "B.Mask" "B.Paste")
			(net "XP5R0V_BT")
		)
		(pad "2" smd rect
			(at -0.5334 0)
			(size 0.7112 0.6096)
			(layers "B.Cu" "B.Mask" "B.Paste")
			(net "UNNAMED_516_CAPACITOR_I27_1")
		)
		(zone
			(layer "B.Cu")
			(hatch none 0.5)
			(connect_pads
				(clearance 0)
			)
			(min_thickness 0.25)
			(keepout
				(tracks not_allowed)
				(vias allowed)
				(pads allowed)
				(copperpour not_allowed)
				(footprints allowed)
			)
			(placement
				(enabled no)
				(sheetname "")
			)
			(fill
				(thermal_gap 0.5)
				(thermal_bridge_width 0.5)
				(island_removal_mode 0)
			)
			(polygon
				(pts
					(xy 41.7068 -98.9838) (xy 41.7068 -98.3742) (xy 41.8592 -98.3742) (xy 41.8592 -98.9838)
				)
			)
		)
		(zone
			(layer "B.Cu")
			(hatch none 0.5)
			(connect_pads
				(clearance 0)
			)
			(min_thickness 0.25)
			(keepout
				(tracks allowed)
				(vias not_allowed)
				(pads allowed)
				(copperpour not_allowed)
				(footprints allowed)
			)
			(placement
				(enabled no)
				(sheetname "")
			)
			(fill
				(thermal_gap 0.5)
				(thermal_bridge_width 0.5)
				(island_removal_mode 0)
			)
			(polygon
				(pts
					(xy 41.7068 -98.9838) (xy 41.7068 -98.3742) (xy 41.8592 -98.3742) (xy 41.8592 -98.9838)
				)
			)
		)
	)
	(footprint ""
		(layer "B.Cu")
		(at 111.847122 -55.323232 -90)
		(property "Reference" "C223"
			(at -2.207768 -0.008128 270)
			(unlocked yes)
			(layer "B.SilkS")
			(effects
				(font
					(size 0.635 0.4064)
					(thickness 0.1524)
				)
				(justify mirror)
			)
		)
		(property "Value" "VAL*"
			(at 0 3.718306 270)
			(unlocked yes)
			(layer "B.Fab")
			(hide yes)
			(effects
				(font
					(size 0.7874 0.5842)
					(thickness 0.127)
				)
				(justify mirror)
			)
		)
		(property "Tolerance" "TOL*"
			(at 0 4.861306 270)
			(unlocked yes)
			(layer "Cmts.User")
			(hide yes)
			(effects
				(font
					(size 0.7874 0.5842)
					(thickness 0.127)
				)
				(justify mirror)
			)
		)
		(property "User Part Number" "PARTNUM*"
			(at 0 2.575306 270)
			(unlocked yes)
			(layer "Cmts.User")
			(hide yes)
			(effects
				(font
					(size 0.7874 0.5842)
					(thickness 0.127)
				)
				(justify mirror)
			)
		)
		(property "Device Type" "CAPACITOR-G105-0B104-CK,0.1UF,A"
			(at 0 1.432306 270)
			(unlocked yes)
			(layer "B.Fab")
			(hide yes)
			(effects
				(font
					(size 0.7874 0.5842)
					(thickness 0.127)
				)
				(justify mirror)
			)
		)
		(duplicate_pad_numbers_are_jumpers no)
		(fp_line
			(start -0.970026 0.4699)
			(end 0.970026 0.4699)
			(stroke
				(width 0.1)
				(type default)
			)
			(layer "B.SilkS")
		)
		(fp_line
			(start 0.970026 0.4699)
			(end 0.970026 -0.4699)
			(stroke
				(width 0.1)
				(type default)
			)
			(layer "B.SilkS")
		)
		(fp_line
			(start -0.970026 -0.4699)
			(end -0.970026 0.4699)
			(stroke
				(width 0.1)
				(type default)
			)
			(layer "B.SilkS")
		)
		(fp_line
			(start 0.970026 -0.4699)
			(end -0.970026 -0.4699)
			(stroke
				(width 0.1)
				(type default)
			)
			(layer "B.SilkS")
		)
		(fp_poly
			(pts
				(xy 0.970026 0.4699) (xy -0.970026 0.4699) (xy -0.970026 -0.4699) (xy 0.970026 -0.4699)
			)
			(stroke
				(width 0)
				(type default)
			)
			(fill no)
			(layer "B.CrtYd")
		)
		(fp_line
			(start -0.508 0.3048)
			(end 0.508 0.3048)
			(stroke
				(width 0.1)
				(type default)
			)
			(layer "B.Fab")
		)
		(fp_line
			(start 0.508 0.3048)
			(end 0.508 -0.3048)
			(stroke
				(width 0.1)
				(type default)
			)
			(layer "B.Fab")
		)
		(fp_line
			(start -0.508 -0.3048)
			(end -0.508 0.3048)
			(stroke
				(width 0.1)
				(type default)
			)
			(layer "B.Fab")
		)
		(fp_line
			(start 0.508 -0.3048)
			(end -0.508 -0.3048)
			(stroke
				(width 0.1)
				(type default)
			)
			(layer "B.Fab")
		)
		(pad "1" smd circle
			(at 0.500126 0 90)
			(size 0.635 0.635)
			(layers "B.Cu" "B.Mask" "B.Paste")
			(net "XP3R3V_FPGA")
		)
		(pad "2" smd circle
			(at -0.500126 0 90)
			(size 0.635 0.635)
			(layers "B.Cu" "B.Mask" "B.Paste")
			(net "SG")
		)
	)
	(footprint ""
		(layer "B.Cu")
		(at 99.5426 -64.2874 90)
		(property "Reference" "R173"
			(at 3.4036 0.11303 270)
			(unlocked yes)
			(layer "B.SilkS")
			(effects
				(font
					(size 0.7874 0.5842)
					(thickness 0.1524)
				)
				(justify mirror)
			)
		)
		(property "Value" "VAL*"
			(at -0.02032 2.13233 90)
			(unlocked yes)
			(layer "B.Fab")
			(hide yes)
			(effects
				(font
					(size 0.7874 0.5842)
					(thickness 0.1524)
				)
				(justify mirror)
			)
		)
		(property "Tolerance" "TOL*"
			(at -0.044704 3.05435 90)
			(unlocked yes)
			(layer "Cmts.User")
			(hide yes)
			(effects
				(font
					(size 0.7874 0.5842)
					(thickness 0.1524)
				)
				(justify mirror)
			)
		)
		(property "User Part Number" "PARTNUM*"
			(at -0.02032 4.024884 90)
			(unlocked yes)
			(layer "Cmts.User")
			(hide yes)
			(effects
				(font
					(size 0.7874 0.5842)
					(thickness 0.1524)
				)
				(justify mirror)
			)
		)
		(property "Device Type" "RESISTOR-G155-14701-01,4.7KOHMA"
			(at -0.008382 1.210564 90)
			(unlocked yes)
			(layer "B.Fab")
			(hide yes)
			(effects
				(font
					(size 0.7874 0.5842)
					(thickness 0.1524)
				)
				(justify mirror)
			)
		)
		(duplicate_pad_numbers_are_jumpers no)
		(fp_line
			(start 1.143 -0.5588)
			(end 1.143 0.5588)
			(stroke
				(width 0.1)
				(type default)
			)
			(layer "B.SilkS")
		)
		(fp_line
			(start -1.143 -0.5588)
			(end 1.143 -0.5588)
			(stroke
				(width 0.1)
				(type default)
			)
			(layer "B.SilkS")
		)
		(fp_line
			(start 1.143 0.5588)
			(end -1.143 0.5588)
			(stroke
				(width 0.1)
				(type default)
			)
			(layer "B.SilkS")
		)
		(fp_line
			(start -1.143 0.5588)
			(end -1.143 -0.5588)
			(stroke
				(width 0.1)
				(type default)
			)
			(layer "B.SilkS")
		)
		(fp_poly
			(pts
				(xy 1.143 0.5588) (xy -1.143 0.5588) (xy -1.143 -0.5588) (xy 1.143 -0.5588)
			)
			(stroke
				(width 0)
				(type default)
			)
			(fill no)
			(layer "B.CrtYd")
		)
		(fp_line
			(start 0.508 -0.3048)
			(end 0.508 0.3048)
			(stroke
				(width 0.1)
				(type default)
			)
			(layer "B.Fab")
		)
		(fp_line
			(start -0.508 -0.3048)
			(end 0.508 -0.3048)
			(stroke
				(width 0.1)
				(type default)
			)
			(layer "B.Fab")
		)
		(fp_line
			(start 0.508 0.3048)
			(end -0.508 0.3048)
			(stroke
				(width 0.1)
				(type default)
			)
			(layer "B.Fab")
		)
		(fp_line
			(start -0.508 0.3048)
			(end -0.508 -0.3048)
			(stroke
				(width 0.1)
				(type default)
			)
			(layer "B.Fab")
		)
		(pad "1" smd rect
			(at 0.5334 0 270)
			(size 0.7112 0.6096)
			(layers "B.Cu" "B.Mask" "B.Paste")
			(net "SG")
		)
		(pad "2" smd rect
			(at -0.5334 0 270)
			(size 0.7112 0.6096)
			(layers "B.Cu" "B.Mask" "B.Paste")
			(net "FPGA_IO_1")
		)
		(zone
			(layer "B.Cu")
			(hatch none 0.5)
			(connect_pads
				(clearance 0)
			)
			(min_thickness 0.25)
			(keepout
				(tracks not_allowed)
				(vias allowed)
				(pads allowed)
				(copperpour not_allowed)
				(footprints allowed)
			)
			(placement
				(enabled no)
				(sheetname "")
			)
			(fill
				(thermal_gap 0.5)
				(thermal_bridge_width 0.5)
				(island_removal_mode 0)
			)
			(polygon
				(pts
					(xy 99.8474 -64.3636) (xy 99.2378 -64.3636) (xy 99.2378 -64.2112) (xy 99.8474 -64.2112)
				)
			)
		)
		(zone
			(layer "B.Cu")
			(hatch none 0.5)
			(connect_pads
				(clearance 0)
			)
			(min_thickness 0.25)
			(keepout
				(tracks allowed)
				(vias not_allowed)
				(pads allowed)
				(copperpour not_allowed)
				(footprints allowed)
			)
			(placement
				(enabled no)
				(sheetname "")
			)
			(fill
				(thermal_gap 0.5)
				(thermal_bridge_width 0.5)
				(island_removal_mode 0)
			)
			(polygon
				(pts
					(xy 99.8474 -64.3636) (xy 99.2378 -64.3636) (xy 99.2378 -64.2112) (xy 99.8474 -64.2112)
				)
			)
		)
	)
	(footprint ""
		(layer "B.Cu")
		(at 116.346986 -46.823122)
		(property "Reference" "R502"
			(at -42.940986 2.658872 0)
			(unlocked yes)
			(layer "B.SilkS")
			(effects
				(font
					(size 0.635 0.4064)
					(thickness 0.1524)
				)
				(justify mirror)
			)
		)
		(property "Value" "VAL*"
			(at 0 3.718306 0)
			(unlocked yes)
			(layer "B.Fab")
			(hide yes)
			(effects
				(font
					(size 0.7874 0.5842)
					(thickness 0.127)
				)
				(justify mirror)
			)
		)
		(property "Tolerance" "TOL*"
			(at 0 4.861306 0)
			(unlocked yes)
			(layer "Cmts.User")
			(hide yes)
			(effects
				(font
					(size 0.7874 0.5842)
					(thickness 0.127)
				)
				(justify mirror)
			)
		)
		(property "User Part Number" "PARTNUM*"
			(at 0 2.575306 0)
			(unlocked yes)
			(layer "Cmts.User")
			(hide yes)
			(effects
				(font
					(size 0.7874 0.5842)
					(thickness 0.127)
				)
				(justify mirror)
			)
		)
		(property "Device Type" "RESISTOR-G155-12201-01,2.2KOHMA"
			(at 0 1.432306 0)
			(unlocked yes)
			(layer "B.Fab")
			(hide yes)
			(effects
				(font
					(size 0.7874 0.5842)
					(thickness 0.127)
				)
				(justify mirror)
			)
		)
		(duplicate_pad_numbers_are_jumpers no)
		(fp_line
			(start -0.970026 -0.4699)
			(end -0.970026 0.4699)
			(stroke
				(width 0.1)
				(type default)
			)
			(layer "B.SilkS")
		)
		(fp_line
			(start -0.970026 0.4699)
			(end 0.970026 0.4699)
			(stroke
				(width 0.1)
				(type default)
			)
			(layer "B.SilkS")
		)
		(fp_line
			(start 0.970026 -0.4699)
			(end -0.970026 -0.4699)
			(stroke
				(width 0.1)
				(type default)
			)
			(layer "B.SilkS")
		)
		(fp_line
			(start 0.970026 0.4699)
			(end 0.970026 -0.4699)
			(stroke
				(width 0.1)
				(type default)
			)
			(layer "B.SilkS")
		)
		(fp_poly
			(pts
				(xy 0.970026 0.4699) (xy -0.970026 0.4699) (xy -0.970026 -0.4699) (xy 0.970026 -0.4699)
			)
			(stroke
				(width 0)
				(type default)
			)
			(fill no)
			(layer "B.CrtYd")
		)
		(fp_line
			(start -0.508 -0.3048)
			(end -0.508 0.3048)
			(stroke
				(width 0.1)
				(type default)
			)
			(layer "B.Fab")
		)
		(fp_line
			(start -0.508 0.3048)
			(end 0.508 0.3048)
			(stroke
				(width 0.1)
				(type default)
			)
			(layer "B.Fab")
		)
		(fp_line
			(start 0.508 -0.3048)
			(end -0.508 -0.3048)
			(stroke
				(width 0.1)
				(type default)
			)
			(layer "B.Fab")
		)
		(fp_line
			(start 0.508 0.3048)
			(end 0.508 -0.3048)
			(stroke
				(width 0.1)
				(type default)
			)
			(layer "B.Fab")
		)
		(pad "1" smd circle
			(at 0.500126 0 180)
			(size 0.635 0.635)
			(layers "B.Cu" "B.Mask" "B.Paste")
			(net "XP3R3V_FPGA")
		)
		(pad "2" smd circle
			(at -0.500126 0 180)
			(size 0.635 0.635)
			(layers "B.Cu" "B.Mask" "B.Paste")
			(net "FPGA_IN_MAC_10MHZ_OUT")
		)
	)
	(footprint ""
		(layer "B.Cu")
		(at 138.4808 -70.9168 90)
		(property "Reference" "R403"
			(at 0.9652 -4.78917 270)
			(unlocked yes)
			(layer "B.SilkS")
			(effects
				(font
					(size 0.7874 0.5842)
					(thickness 0.1524)
				)
				(justify mirror)
			)
		)
		(property "Value" "VAL*"
			(at -0.02032 2.13233 90)
			(unlocked yes)
			(layer "B.Fab")
			(hide yes)
			(effects
				(font
					(size 0.7874 0.5842)
					(thickness 0.1524)
				)
				(justify mirror)
			)
		)
		(property "Tolerance" "TOL*"
			(at -0.044704 3.05435 90)
			(unlocked yes)
			(layer "Cmts.User")
			(hide yes)
			(effects
				(font
					(size 0.7874 0.5842)
					(thickness 0.1524)
				)
				(justify mirror)
			)
		)
		(property "User Part Number" "PARTNUM*"
			(at -0.02032 4.024884 90)
			(unlocked yes)
			(layer "Cmts.User")
			(hide yes)
			(effects
				(font
					(size 0.7874 0.5842)
					(thickness 0.1524)
				)
				(justify mirror)
			)
		)
		(property "Device Type" "RESISTOR-G155-11002-01,10KOHM,A"
			(at -0.008382 1.210564 90)
			(unlocked yes)
			(layer "B.Fab")
			(hide yes)
			(effects
				(font
					(size 0.7874 0.5842)
					(thickness 0.1524)
				)
				(justify mirror)
			)
		)
		(duplicate_pad_numbers_are_jumpers no)
		(fp_line
			(start 1.143 -0.5588)
			(end 1.143 0.5588)
			(stroke
				(width 0.1)
				(type default)
			)
			(layer "B.SilkS")
		)
		(fp_line
			(start -1.143 -0.5588)
			(end 1.143 -0.5588)
			(stroke
				(width 0.1)
				(type default)
			)
			(layer "B.SilkS")
		)
		(fp_line
			(start 1.143 0.5588)
			(end -1.143 0.5588)
			(stroke
				(width 0.1)
				(type default)
			)
			(layer "B.SilkS")
		)
		(fp_line
			(start -1.143 0.5588)
			(end -1.143 -0.5588)
			(stroke
				(width 0.1)
				(type default)
			)
			(layer "B.SilkS")
		)
		(fp_rect
			(start 1.143 0.5588)
			(end -1.143 -0.5588)
			(stroke
				(width 0)
				(type default)
			)
			(fill no)
			(layer "B.CrtYd")
		)
		(fp_line
			(start 0.508 -0.3048)
			(end 0.508 0.3048)
			(stroke
				(width 0.1)
				(type default)
			)
			(layer "B.Fab")
		)
		(fp_line
			(start -0.508 -0.3048)
			(end 0.508 -0.3048)
			(stroke
				(width 0.1)
				(type default)
			)
			(layer "B.Fab")
		)
		(fp_line
			(start 0.508 0.3048)
			(end -0.508 0.3048)
			(stroke
				(width 0.1)
				(type default)
			)
			(layer "B.Fab")
		)
		(fp_line
			(start -0.508 0.3048)
			(end -0.508 -0.3048)
			(stroke
				(width 0.1)
				(type default)
			)
			(layer "B.Fab")
		)
		(pad "1" smd rect
			(at 0.5334 0 270)
			(size 0.7112 0.6096)
			(layers "B.Cu" "B.Mask" "B.Paste")
			(net "XP3R3V_FPGA")
		)
		(pad "2" smd rect
			(at -0.5334 0 270)
			(size 0.7112 0.6096)
			(layers "B.Cu" "B.Mask" "B.Paste")
			(net "FPGA_TDO")
		)
		(zone
			(layer "B.Cu")
			(hatch none 0.5)
			(connect_pads
				(clearance 0)
			)
			(min_thickness 0.25)
			(keepout
				(tracks not_allowed)
				(vias allowed)
				(pads allowed)
				(copperpour not_allowed)
				(footprints allowed)
			)
			(placement
				(enabled no)
				(sheetname "")
			)
			(fill
				(thermal_gap 0.5)
				(thermal_bridge_width 0.5)
				(island_removal_mode 0)
			)
			(polygon
				(pts
					(xy 138.7856 -70.993) (xy 138.176 -70.993) (xy 138.176 -70.8406) (xy 138.7856 -70.8406)
				)
			)
		)
		(zone
			(layer "B.Cu")
			(hatch none 0.5)
			(connect_pads
				(clearance 0)
			)
			(min_thickness 0.25)
			(keepout
				(tracks allowed)
				(vias not_allowed)
				(pads allowed)
				(copperpour not_allowed)
				(footprints allowed)
			)
			(placement
				(enabled no)
				(sheetname "")
			)
			(fill
				(thermal_gap 0.5)
				(thermal_bridge_width 0.5)
				(island_removal_mode 0)
			)
			(polygon
				(pts
					(xy 138.7856 -70.993) (xy 138.176 -70.993) (xy 138.176 -70.8406) (xy 138.7856 -70.8406)
				)
			)
		)
	)
)
